# T6G (Grand Teton) — schematic netlist excerpt (pin names and nets, part order shuffled) for the footprints in the layout excerpt that follows; sources: Cadence DE-HDL packaged netlist, KiCad conversion of 04192023_DAF0TMB3IC0_F0TG_MB_C_brd_V02_OCP.brd

R4076  Q_RES  0 5% CHIP  pkg 0402LF  page 233 : A = CLK_GEN2_GPU_FPGA_OE_OR_N ; B = CLK_GEN2_GPU_OE_N
PR6541  Q_RES  0 5% CHIP  pkg 0402LF  page 364 : A = NC_P0V9_RETIMER_CPU1_IMON5 ; B = GND

(kicad_pcb
	(version 20260206)
	(generator "pcbnew")
	(generator_version "10.0")
	(general
		(thickness 1.6)
		(legacy_teardrops no)
	)
	(paper "A4")
	(title_block
		(title "04192023_DAF0TMB3IC0_F0TG_MB_C_brd_V02_OCP.brd")
		(comment 1 "Grand Teton / footprints 4556-4557 of 8354")
	)
	(layers
		(0 "F.Cu" signal "TOP")
		(4 "In1.Cu" signal "GND")
		(6 "In2.Cu" signal "IN1")
		(8 "In3.Cu" signal "GND1")
		(10 "In4.Cu" signal "IN2")
		(12 "In5.Cu" signal "GND2")
		(14 "In6.Cu" signal "IN3")
		(16 "In7.Cu" signal "GND3")
		(18 "In8.Cu" signal "VCC")
		(20 "In9.Cu" signal "VCC1")
		(22 "In10.Cu" signal "GND4")
		(24 "In11.Cu" signal "IN4")
		(26 "In12.Cu" signal "GND5")
		(28 "In13.Cu" signal "IN5")
		(30 "In14.Cu" signal "GND6")
		(32 "In15.Cu" signal "IN6")
		(34 "In16.Cu" signal "GND7")
		(2 "B.Cu" signal "BOTTOM")
		(9 "F.Adhes" user "F.Adhesive")
		(11 "B.Adhes" user "B.Adhesive")
		(13 "F.Paste" user "Package Geometry/Pastemask Top")
		(15 "B.Paste" user "Package Geometry/Pastemask Bottom")
		(5 "F.SilkS" user "Ref Des/Silkscreen Top")
		(7 "B.SilkS" user "Ref Des/Silkscreen Bottom")
		(1 "F.Mask" user "Board Geometry/Soldermask Top")
		(3 "B.Mask" user "Board Geometry/Soldermask Bottom")
		(17 "Dwgs.User" user "User.Drawings")
		(19 "Cmts.User" user "User.Comments")
		(21 "Eco1.User" user "User.Eco1")
		(23 "Eco2.User" user "User.Eco2")
		(25 "Edge.Cuts" user "Board Geometry/Outline")
		(27 "Margin" user)
		(31 "F.CrtYd" user "Package Geometry/Place Bound Top")
		(29 "B.CrtYd" user "Package Geometry/Place Bound Bottom")
		(35 "F.Fab" user "Ref Des/Assembly Top")
		(33 "B.Fab" user "Ref Des/Assembly Bottom")
	)
	(footprint ""
		(layer "F.Cu")
		(at 14.257782 -416.050984 90)
		(property "Reference" "PR6541"
			(at 0 0 90)
			(layer "F.SilkS")
			(hide yes)
			(effects
				(font
					(size 1.27 1.27)
				)
			)
		)
		(property "Value" ""
			(at 0 0 90)
			(layer "F.Fab")
			(effects
				(font
					(size 1.27 1.27)
				)
			)
		)
		(duplicate_pad_numbers_are_jumpers no)
		(fp_line
			(start 0.7874 -0.4064)
			(end 0.7874 0.4064)
			(stroke
				(width 0.1524)
				(type default)
			)
			(layer "F.SilkS")
		)
		(fp_line
			(start -0.7874 -0.4064)
			(end 0.7874 -0.4064)
			(stroke
				(width 0.1524)
				(type default)
			)
			(layer "F.SilkS")
		)
		(fp_line
			(start 0.7874 0.4064)
			(end -0.7874 0.4064)
			(stroke
				(width 0.1524)
				(type default)
			)
			(layer "F.SilkS")
		)
		(fp_line
			(start -0.7874 0.4064)
			(end -0.7874 -0.4064)
			(stroke
				(width 0.1524)
				(type default)
			)
			(layer "F.SilkS")
		)
		(fp_line
			(start -0.12065 -0.305054)
			(end -0.12065 -0.2794)
			(stroke
				(width 0.1)
				(type default)
			)
			(layer "F.Fab")
		)
		(fp_line
			(start -0.67945 -0.305054)
			(end -0.12065 -0.305054)
			(stroke
				(width 0.1)
				(type default)
			)
			(layer "F.Fab")
		)
		(fp_line
			(start 0.67945 -0.3048)
			(end 0.67945 0.3048)
			(stroke
				(width 0.1)
				(type default)
			)
			(layer "F.Fab")
		)
		(fp_line
			(start 0.12065 -0.3048)
			(end 0.67945 -0.3048)
			(stroke
				(width 0.1)
				(type default)
			)
			(layer "F.Fab")
		)
		(fp_line
			(start 0.12065 -0.2794)
			(end 0.12065 -0.3048)
			(stroke
				(width 0.1)
				(type default)
			)
			(layer "F.Fab")
		)
		(fp_line
			(start -0.12065 -0.2794)
			(end 0.12065 -0.2794)
			(stroke
				(width 0.1)
				(type default)
			)
			(layer "F.Fab")
		)
		(fp_line
			(start 0.120396 0.2794)
			(end -0.12065 0.2794)
			(stroke
				(width 0.1)
				(type default)
			)
			(layer "F.Fab")
		)
		(fp_line
			(start -0.12065 0.2794)
			(end -0.12065 0.3048)
			(stroke
				(width 0.1)
				(type default)
			)
			(layer "F.Fab")
		)
		(fp_line
			(start 0.67945 0.3048)
			(end 0.120396 0.3048)
			(stroke
				(width 0.1)
				(type default)
			)
			(layer "F.Fab")
		)
		(fp_line
			(start 0.120396 0.3048)
			(end 0.120396 0.2794)
			(stroke
				(width 0.1)
				(type default)
			)
			(layer "F.Fab")
		)
		(fp_line
			(start -0.12065 0.3048)
			(end -0.67945 0.3048)
			(stroke
				(width 0.1)
				(type default)
			)
			(layer "F.Fab")
		)
		(fp_line
			(start -0.67945 0.3048)
			(end -0.67945 -0.305054)
			(stroke
				(width 0.1)
				(type default)
			)
			(layer "F.Fab")
		)
		(pad "1" smd circle
			(at -0.40005 0 90)
			(size 0 0)
			(layers "F.Cu" "F.Mask" "F.Paste")
			(net "NC_P0V9_RETIMER_CPU1_IMON5")
		)
		(pad "2" smd circle
			(at 0.40005 0 90)
			(size 0 0)
			(layers "F.Cu" "F.Mask" "F.Paste")
			(net "GND")
		)
	)
	(footprint ""
		(layer "F.Cu")
		(at 16.039592 -139.25804 -90)
		(property "Reference" "R4076"
			(at 0 0 270)
			(layer "F.SilkS")
			(hide yes)
			(effects
				(font
					(size 1.27 1.27)
				)
			)
		)
		(property "Value" ""
			(at 0 0 270)
			(layer "F.Fab")
			(effects
				(font
					(size 1.27 1.27)
				)
			)
		)
		(duplicate_pad_numbers_are_jumpers no)
		(fp_line
			(start -0.7874 0.4064)
			(end -0.7874 -0.4064)
			(stroke
				(width 0.1524)
				(type default)
			)
			(layer "F.SilkS")
		)
		(fp_line
			(start 0.7874 0.4064)
			(end -0.7874 0.4064)
			(stroke
				(width 0.1524)
				(type default)
			)
			(layer "F.SilkS")
		)
		(fp_line
			(start -0.7874 -0.4064)
			(end 0.7874 -0.4064)
			(stroke
				(width 0.1524)
				(type default)
			)
			(layer "F.SilkS")
		)
		(fp_line
			(start 0.7874 -0.4064)
			(end 0.7874 0.4064)
			(stroke
				(width 0.1524)
				(type default)
			)
			(layer "F.SilkS")
		)
		(fp_line
			(start -0.67945 0.3048)
			(end -0.67945 -0.305054)
			(stroke
				(width 0.1)
				(type default)
			)
			(layer "F.Fab")
		)
		(fp_line
			(start -0.12065 0.3048)
			(end -0.67945 0.3048)
			(stroke
				(width 0.1)
				(type default)
			)
			(layer "F.Fab")
		)
		(fp_line
			(start 0.120396 0.3048)
			(end 0.120396 0.2794)
			(stroke
				(width 0.1)
				(type default)
			)
			(layer "F.Fab")
		)
		(fp_line
			(start 0.67945 0.3048)
			(end 0.120396 0.3048)
			(stroke
				(width 0.1)
				(type default)
			)
			(layer "F.Fab")
		)
		(fp_line
			(start -0.12065 0.2794)
			(end -0.12065 0.3048)
			(stroke
				(width 0.1)
				(type default)
			)
			(layer "F.Fab")
		)
		(fp_line
			(start 0.120396 0.2794)
			(end -0.12065 0.2794)
			(stroke
				(width 0.1)
				(type default)
			)
			(layer "F.Fab")
		)
		(fp_line
			(start -0.12065 -0.2794)
			(end 0.12065 -0.2794)
			(stroke
				(width 0.1)
				(type default)
			)
			(layer "F.Fab")
		)
		(fp_line
			(start 0.12065 -0.2794)
			(end 0.12065 -0.3048)
			(stroke
				(width 0.1)
				(type default)
			)
			(layer "F.Fab")
		)
		(fp_line
			(start 0.12065 -0.3048)
			(end 0.67945 -0.3048)
			(stroke
				(width 0.1)
				(type default)
			)
			(layer "F.Fab")
		)
		(fp_line
			(start 0.67945 -0.3048)
			(end 0.67945 0.3048)
			(stroke
				(width 0.1)
				(type default)
			)
			(layer "F.Fab")
		)
		(fp_line
			(start -0.67945 -0.305054)
			(end -0.12065 -0.305054)
			(stroke
				(width 0.1)
				(type default)
			)
			(layer "F.Fab")
		)
		(fp_line
			(start -0.12065 -0.305054)
			(end -0.12065 -0.2794)
			(stroke
				(width 0.1)
				(type default)
			)
			(layer "F.Fab")
		)
		(pad "1" smd circle
			(at -0.40005 0 270)
			(size 0 0)
			(layers "F.Cu" "F.Mask" "F.Paste")
			(net "CLK_GEN2_GPU_FPGA_OE_OR_N")
		)
		(pad "2" smd circle
			(at 0.40005 0 270)
			(size 0 0)
			(layers "F.Cu" "F.Mask" "F.Paste")
			(net "CLK_GEN2_GPU_OE_N")
		)
	)
)
